# BASEBOARD_FAB2 (Tioga Pass) — schematic netlist excerpt (pin names and nets, part order shuffled) for the footprints in the layout excerpt that follows; sources: Cadence DE-HDL packaged netlist, KiCad conversion of Wiwynn_Tioga_Pass_MB.brd

C7G10  CAP  0.22UF 16V 10% X7R  pkg 0402  page 105 : A = P3E_CPU0_PE2_SS_TXN<13> ; B = P3E_CPU0_PE2_SS_C_TXN<13>
R9W14  RES  20.0 1% CHIP  pkg 0402  page 248 : A = SMB_PEHPCPU0_STBY_LVC3_R_SCL ; B = SMB_PEHPCPU0_STBY_LVC3_SCL
R3D17  RES  240 1.0% EMPTY  pkg 0402  page 90 : A = PVCCIO_CPU1 ; B = PU_CPU1_SOCKET_ID_1

(kicad_pcb
	(version 20260206)
	(generator "pcbnew")
	(generator_version "10.0")
	(general
		(thickness 1.6)
		(legacy_teardrops no)
	)
	(paper "A4")
	(title_block
		(title "Wiwynn_Tioga_Pass_MB.brd")
		(comment 1 "Tioga Pass / footprints 2036-2038 of 4770")
	)
	(layers
		(0 "F.Cu" signal "TOP")
		(4 "In1.Cu" signal "L2GND")
		(6 "In2.Cu" signal "L3")
		(8 "In3.Cu" signal "L4GND")
		(10 "In4.Cu" signal "L5")
		(12 "In5.Cu" signal "L6GND")
		(14 "In6.Cu" signal "L7VCC")
		(16 "In7.Cu" signal "L8VCC")
		(18 "In8.Cu" signal "L9GND")
		(20 "In9.Cu" signal "L10")
		(22 "In10.Cu" signal "L11GND")
		(24 "In11.Cu" signal "L12")
		(26 "In12.Cu" signal "L13GND")
		(2 "B.Cu" signal "BOTTOM")
		(9 "F.Adhes" user "F.Adhesive")
		(11 "B.Adhes" user "B.Adhesive")
		(13 "F.Paste" user "Package Geometry/Pastemask Top")
		(15 "B.Paste" user "Package Geometry/Pastemask Bottom")
		(5 "F.SilkS" user "Ref Des/Silkscreen Top")
		(7 "B.SilkS" user "Ref Des/Silkscreen Bottom")
		(1 "F.Mask" user "Board Geometry/Soldermask Top")
		(3 "B.Mask" user "Board Geometry/Soldermask Bottom")
		(17 "Dwgs.User" user "User.Drawings")
		(19 "Cmts.User" user "User.Comments")
		(21 "Eco1.User" user "User.Eco1")
		(23 "Eco2.User" user "User.Eco2")
		(25 "Edge.Cuts" user "Board Geometry/Outline")
		(27 "Margin" user)
		(31 "F.CrtYd" user "Package Geometry/Place Bound Top")
		(29 "B.CrtYd" user "Package Geometry/Place Bound Bottom")
		(35 "F.Fab" user "Ref Des/Assembly Top")
		(33 "B.Fab" user "Ref Des/Assembly Bottom")
	)
	(footprint ""
		(layer "F.Cu")
		(at 116.3066 -72.263 90)
		(property "Reference" "R3D17"
			(at 0 0 90)
			(layer "F.SilkS")
			(hide yes)
			(effects
				(font
					(size 1.27 1.27)
				)
			)
		)
		(property "Value" ""
			(at 0 0 90)
			(layer "F.Fab")
			(effects
				(font
					(size 1.27 1.27)
				)
			)
		)
		(duplicate_pad_numbers_are_jumpers no)
		(fp_poly
			(pts
				(xy -0.2794 -0.1016) (xy 0.2794 -0.1016) (xy 0.2794 0.9906) (xy -0.2794 0.9906)
			)
			(stroke
				(width 0)
				(type default)
			)
			(fill no)
			(layer "F.CrtYd")
		)
		(fp_line
			(start 0.2794 -0.1016)
			(end -0.2794 -0.1016)
			(stroke
				(width 0.1)
				(type default)
			)
			(layer "F.Fab")
		)
		(fp_line
			(start -0.2794 -0.1016)
			(end -0.2794 0.9906)
			(stroke
				(width 0.1)
				(type default)
			)
			(layer "F.Fab")
		)
		(fp_line
			(start 0.2794 0.9906)
			(end 0.2794 -0.1016)
			(stroke
				(width 0.1)
				(type default)
			)
			(layer "F.Fab")
		)
		(fp_line
			(start -0.2794 0.9906)
			(end 0.2794 0.9906)
			(stroke
				(width 0.1)
				(type default)
			)
			(layer "F.Fab")
		)
		(pad "1" smd rect
			(at 0 0 90)
			(size 0.508 0.508)
			(layers "F.Cu" "F.Mask" "F.Paste")
			(net "PVCCIO_CPU1")
		)
		(pad "2" smd rect
			(at 0 0.889 90)
			(size 0.508 0.508)
			(layers "F.Cu" "F.Mask" "F.Paste")
			(net "PU_CPU1_SOCKET_ID_1")
		)
		(zone
			(layer "F.Cu")
			(hatch none 0.5)
			(connect_pads
				(clearance 0)
			)
			(min_thickness 0.25)
			(keepout
				(tracks allowed)
				(vias not_allowed)
				(pads allowed)
				(copperpour not_allowed)
				(footprints allowed)
			)
			(placement
				(enabled no)
				(sheetname "")
			)
			(fill
				(thermal_gap 0.5)
				(thermal_bridge_width 0.5)
				(island_removal_mode 0)
			)
			(polygon
				(pts
					(xy 116.5606 -72.009) (xy 116.5606 -72.517) (xy 116.9416 -72.517) (xy 116.9416 -72.009)
				)
			)
		)
		(zone
			(layer "F.Cu")
			(hatch none 0.5)
			(connect_pads
				(clearance 0)
			)
			(min_thickness 0.25)
			(keepout
				(tracks not_allowed)
				(vias allowed)
				(pads allowed)
				(copperpour not_allowed)
				(footprints allowed)
			)
			(placement
				(enabled no)
				(sheetname "")
			)
			(fill
				(thermal_gap 0.5)
				(thermal_bridge_width 0.5)
				(island_removal_mode 0)
			)
			(polygon
				(pts
					(xy 116.9416 -72.009) (xy 116.9416 -72.517) (xy 116.5606 -72.517) (xy 116.5606 -72.009)
				)
			)
		)
	)
	(footprint ""
		(layer "F.Cu")
		(at 367.966244 -10.916158)
		(property "Reference" "C7G10"
			(at 0 0 0)
			(layer "F.SilkS")
			(hide yes)
			(effects
				(font
					(size 1.27 1.27)
				)
			)
		)
		(property "Value" ""
			(at 0 0 0)
			(layer "F.Fab")
			(effects
				(font
					(size 1.27 1.27)
				)
			)
		)
		(duplicate_pad_numbers_are_jumpers no)
		(fp_rect
			(start -0.3048 0.9906)
			(end 0.3048 -0.1016)
			(stroke
				(width 0)
				(type default)
			)
			(fill no)
			(layer "F.CrtYd")
		)
		(fp_line
			(start -0.3048 -0.1016)
			(end -0.3048 0.9906)
			(stroke
				(width 0.1)
				(type default)
			)
			(layer "F.Fab")
		)
		(fp_line
			(start -0.3048 0.9906)
			(end 0.3048 0.9906)
			(stroke
				(width 0.1)
				(type default)
			)
			(layer "F.Fab")
		)
		(fp_line
			(start 0.3048 -0.1016)
			(end -0.3048 -0.1016)
			(stroke
				(width 0.1)
				(type default)
			)
			(layer "F.Fab")
		)
		(fp_line
			(start 0.3048 0.9906)
			(end 0.3048 -0.1016)
			(stroke
				(width 0.1)
				(type default)
			)
			(layer "F.Fab")
		)
		(pad "1" smd rect
			(at 0 0)
			(size 0.508 0.508)
			(layers "F.Cu" "F.Mask" "F.Paste")
			(net "P3E_CPU0_PE2_SS_TXN<13>")
		)
		(pad "2" smd rect
			(at 0 0.889)
			(size 0.508 0.508)
			(layers "F.Cu" "F.Mask" "F.Paste")
			(net "P3E_CPU0_PE2_SS_C_TXN<13>")
		)
		(zone
			(layer "F.Cu")
			(hatch none 0.5)
			(connect_pads
				(clearance 0)
			)
			(min_thickness 0.25)
			(keepout
				(tracks not_allowed)
				(vias allowed)
				(pads allowed)
				(copperpour not_allowed)
				(footprints allowed)
			)
			(placement
				(enabled no)
				(sheetname "")
			)
			(fill
				(thermal_gap 0.5)
				(thermal_bridge_width 0.5)
				(island_removal_mode 0)
			)
			(polygon
				(pts
					(xy 367.712244 -10.281158) (xy 368.220244 -10.281158) (xy 368.220244 -10.662158) (xy 367.712244 -10.662158)
				)
			)
		)
		(zone
			(layer "F.Cu")
			(hatch none 0.5)
			(connect_pads
				(clearance 0)
			)
			(min_thickness 0.25)
			(keepout
				(tracks allowed)
				(vias not_allowed)
				(pads allowed)
				(copperpour not_allowed)
				(footprints allowed)
			)
			(placement
				(enabled no)
				(sheetname "")
			)
			(fill
				(thermal_gap 0.5)
				(thermal_bridge_width 0.5)
				(island_removal_mode 0)
			)
			(polygon
				(pts
					(xy 367.712244 -10.281158) (xy 368.220244 -10.281158) (xy 368.220244 -10.662158) (xy 367.712244 -10.662158)
				)
			)
		)
	)
	(footprint ""
		(layer "F.Cu")
		(at 420.624 -113.8555 180)
		(property "Reference" "R9W14"
			(at -0.8382 -0.67818 180)
			(unlocked yes)
			(layer "F.SilkS")
			(effects
				(font
					(size 0.4064 0.254)
					(thickness 0.1524)
				)
				(justify left)
			)
		)
		(property "Value" ""
			(at 0 0 180)
			(layer "F.Fab")
			(effects
				(font
					(size 1.27 1.27)
				)
			)
		)
		(duplicate_pad_numbers_are_jumpers no)
		(fp_poly
			(pts
				(xy -0.2794 -0.1016) (xy 0.2794 -0.1016) (xy 0.2794 0.9906) (xy -0.2794 0.9906)
			)
			(stroke
				(width 0)
				(type default)
			)
			(fill no)
			(layer "F.CrtYd")
		)
		(fp_line
			(start 0.2794 0.9906)
			(end 0.2794 -0.1016)
			(stroke
				(width 0.1)
				(type default)
			)
			(layer "F.Fab")
		)
		(fp_line
			(start 0.2794 -0.1016)
			(end -0.2794 -0.1016)
			(stroke
				(width 0.1)
				(type default)
			)
			(layer "F.Fab")
		)
		(fp_line
			(start -0.2794 0.9906)
			(end 0.2794 0.9906)
			(stroke
				(width 0.1)
				(type default)
			)
			(layer "F.Fab")
		)
		(fp_line
			(start -0.2794 -0.1016)
			(end -0.2794 0.9906)
			(stroke
				(width 0.1)
				(type default)
			)
			(layer "F.Fab")
		)
		(pad "1" smd rect
			(at 0 0 180)
			(size 0.508 0.508)
			(layers "F.Cu" "F.Mask" "F.Paste")
			(net "SMB_PEHPCPU0_STBY_LVC3_R_SCL")
		)
		(pad "2" smd rect
			(at 0 0.889 180)
			(size 0.508 0.508)
			(layers "F.Cu" "F.Mask" "F.Paste")
			(net "SMB_PEHPCPU0_STBY_LVC3_SCL")
		)
		(zone
			(layer "F.Cu")
			(hatch none 0.5)
			(connect_pads
				(clearance 0)
			)
			(min_thickness 0.25)
			(keepout
				(tracks not_allowed)
				(vias allowed)
				(pads allowed)
				(copperpour not_allowed)
				(footprints allowed)
			)
			(placement
				(enabled no)
				(sheetname "")
			)
			(fill
				(thermal_gap 0.5)
				(thermal_bridge_width 0.5)
				(island_removal_mode 0)
			)
			(polygon
				(pts
					(xy 420.878 -114.4905) (xy 420.37 -114.4905) (xy 420.37 -114.1095) (xy 420.878 -114.1095)
				)
			)
		)
		(zone
			(layer "F.Cu")
			(hatch none 0.5)
			(connect_pads
				(clearance 0)
			)
			(min_thickness 0.25)
			(keepout
				(tracks allowed)
				(vias not_allowed)
				(pads allowed)
				(copperpour not_allowed)
				(footprints allowed)
			)
			(placement
				(enabled no)
				(sheetname "")
			)
			(fill
				(thermal_gap 0.5)
				(thermal_bridge_width 0.5)
				(island_removal_mode 0)
			)
			(polygon
				(pts
					(xy 420.878 -114.1095) (xy 420.37 -114.1095) (xy 420.37 -114.4905) (xy 420.878 -114.4905)
				)
			)
		)
	)
)
